(kicad_pcb
	(version 20221018)
	(generator pcbnew)
	(general
    (thickness 1.62)
  )
	(paper "A4")
	(title_block
    (title "ECP5 - Datacenter Secure Control Module (DC-SCM)")
    (date "2024-07-01")
    (rev "1.2.1")
		(comment 9 "footprints 92-101 of 506")
	)
	(layers
    (0 "F.Cu" signal)
    (1 "In1.Cu" power)
    (2 "In2.Cu" signal)
    (3 "In3.Cu" power)
    (4 "In4.Cu" power)
    (5 "In5.Cu" signal)
    (6 "In6.Cu" power)
    (31 "B.Cu" signal)
    (32 "B.Adhes" user "B.Adhesive")
    (33 "F.Adhes" user "F.Adhesive")
    (34 "B.Paste" user)
    (35 "F.Paste" user)
    (36 "B.SilkS" user "B.Silkscreen")
    (37 "F.SilkS" user "F.Silkscreen")
    (38 "B.Mask" user)
    (39 "F.Mask" user)
    (40 "Dwgs.User" user "User.Drawings")
    (41 "Cmts.User" user "User.Comments")
    (42 "Eco1.User" user "User.Eco1")
    (43 "Eco2.User" user "User.Eco2")
    (44 "Edge.Cuts" user)
    (45 "Margin" user)
    (46 "B.CrtYd" user "B.Courtyard")
    (47 "F.CrtYd" user "F.Courtyard")
    (48 "B.Fab" user)
    (49 "F.Fab" user)
  )
	(footprint "antmicro-footprints:C_0402_1005Metric" (layer "F.Cu")
    (at 137.15 154.9 -90)
    (descr "Capacitor SMD 0402")
    (tags "capacitor SMD 0402")
    (property "Author" "Antmicro")
    (property "Dielectric" "")
    (property "License" "Apache-2.0")
    (property "MPN" "CC0402MRX5R5BB106")
    (property "Manufacturer" "YAGEO")
    (property "Public" "False")
    (property "Sheetfile" "pcie-conn.kicad_sch")
    (property "Sheetname" "PCIe-connector")
    (property "Val" "10u")
    (property "Voltage" "")
    (property "ki_description" "SMD Multilayer Ceramic Capacitor, 10 µF, 6.3 V, 0402 [1005 Metric], ± 20%, X5R, CC Series")
    (property "ki_keywords" "0402, SMT, CAPACITOR, PASSIVE, MLCC, CERAMIC")
    (attr smd)
    (fp_text reference "C39" (at -2.525 0 90) (layer "F.SilkS")
        (effects (font (size 0.7 0.7) (thickness 0.127)))
    )
    (fp_text value "C_10u_0402" (at 0 1.17 90) (layer "F.Fab")
        (effects (font (size 1 1) (thickness 0.15)))
    )
    (fp_text user "Author: Antmicro" (at -0.939 3.399 -90) (layer "F.Fab") hide
        (effects (font (size 0.7 0.7) (thickness 0.15)) (justify left bottom))
    )
    (fp_text user "${REFERENCE}" (at 0 0 90) (layer "F.Fab")
        (effects (font (size 0.25 0.25) (thickness 0.04)))
    )
    (fp_text user "License: Apache-2.0" (at -0.939 5.799 -90) (layer "F.Fab") hide
        (effects (font (size 0.7 0.7) (thickness 0.15)) (justify left bottom))
    )
    (fp_rect (start -0.925 -0.47) (end 0.925 0.47)
      (stroke (width 0.05) (type default)) (fill none) (layer "F.CrtYd"))
    (fp_line (start -0.494 -0.25) (end 0.504 -0.25)
      (stroke (width 0.15) (type solid)) (layer "F.Fab"))
    (fp_line (start -0.494 0.248) (end -0.494 -0.25)
      (stroke (width 0.15) (type solid)) (layer "F.Fab"))
    (fp_line (start 0.504 -0.25) (end 0.504 0.248)
      (stroke (width 0.15) (type solid)) (layer "F.Fab"))
    (fp_line (start 0.504 0.248) (end -0.494 0.248)
      (stroke (width 0.15) (type solid)) (layer "F.Fab"))
    (pad "1" smd roundrect (at -0.48 0 270) (size 0.59 0.64) (layers "F.Cu" "F.Paste" "F.Mask") (roundrect_rratio 0.25)
      (net 1 "GND") (pintype "passive"))
    (pad "2" smd roundrect (at 0.48 0 270) (size 0.59 0.64) (layers "F.Cu" "F.Paste" "F.Mask") (roundrect_rratio 0.25)
      (net 2 "VCC3V3") (pintype "passive"))
  )
	(footprint "antmicro-footprints:TP_SMD_1mm" (layer "F.Cu")
    (at 115.270001 162.7492 180)
    (property "Author" "Antmicro")
    (property "License" "Apache-2.0")
    (property "MPN" "")
    (property "Manufacturer" "")
    (property "Sheetfile" "pcie-conn.kicad_sch")
    (property "Sheetname" "PCIe-connector")
    (property "exclude_from_bom" "")
    (property "ki_description" "Test point 1mm SMD")
    (property "ki_keywords" "TESTPOINT")
    (attr exclude_from_pos_files exclude_from_bom)
    (fp_text reference "TP1" (at 2.640001 -0.4158 180) (layer "F.SilkS")
        (effects (font (size 0.7 0.7) (thickness 0.15)) (justify left bottom))
    )
    (fp_text value "TP_1mm_SMD" (at 0 1.4 180) (layer "F.Fab")
        (effects (font (size 0.7 0.7) (thickness 0.15)) (justify left bottom))
    )
    (fp_text user "${REFERENCE}" (at -0.5 2.8 180) (layer "F.Fab") hide
        (effects (font (size 0.7 0.7) (thickness 0.15)) (justify left bottom))
    )
    (fp_text user "Author: Antmicro" (at -0.5 4 180) (layer "F.Fab") hide
        (effects (font (size 0.7 0.7) (thickness 0.15)) (justify left bottom))
    )
    (fp_text user "License: Apache-2.0" (at -0.5 5.2 180) (layer "F.Fab") hide
        (effects (font (size 0.7 0.7) (thickness 0.15)) (justify left bottom))
    )
    (fp_circle (center 0 0) (end 0.6 0)
      (stroke (width 0.05) (type default)) (fill none) (layer "F.CrtYd"))
    (pad "1" smd circle (at 0 0 180) (size 1 1) (layers "F.Cu" "F.Mask")
      (net 381 "Net-(J2-~{PEWAKE})") (pinfunction "1") (pintype "passive"))
  )
	(footprint "antmicro-footprints:C_0402_1005Metric" (layer "F.Cu")
    (at 86.1 113.1 90)
    (descr "Capacitor SMD 0402")
    (tags "capacitor SMD 0402")
    (property "Author" "Antmicro")
    (property "Dielectric" "X5R")
    (property "License" "Apache-2.0")
    (property "MPN" "GRM155R61H104KE14D")
    (property "Manufacturer" "Murata")
    (property "Public" "False")
    (property "Sheetfile" "fpga-banks.kicad_sch")
    (property "Sheetname" "FPGA banks")
    (property "Val" "100n")
    (property "Voltage" "50V")
    (property "ki_description" "SMD Multilayer Ceramic Capacitor, 0.1 µF, 50 V, 0402 [1005 Metric], ± 10%, X5R, GRM Series")
    (property "ki_keywords" "0402, SMT, CAPACITOR, PASSIVE, CERAMIC, MLCC")
    (attr smd)
    (fp_text reference "C241" (at 1.295 -1.06 90) (layer "F.SilkS")
        (effects (font (size 0.7 0.7) (thickness 0.127)))
    )
    (fp_text value "C_100n_0402" (at 0 1.17 90) (layer "F.Fab")
        (effects (font (size 1 1) (thickness 0.15)))
    )
    (fp_text user "Author: Antmicro" (at -0.939 3.399 90) (layer "F.Fab") hide
        (effects (font (size 0.7 0.7) (thickness 0.15)) (justify left bottom))
    )
    (fp_text user "License: Apache-2.0" (at -0.939 5.799 90) (layer "F.Fab") hide
        (effects (font (size 0.7 0.7) (thickness 0.15)) (justify left bottom))
    )
    (fp_text user "${REFERENCE}" (at 0 0 90) (layer "F.Fab")
        (effects (font (size 0.25 0.25) (thickness 0.04)))
    )
    (fp_rect (start -0.925 -0.47) (end 0.925 0.47)
      (stroke (width 0.05) (type default)) (fill none) (layer "F.CrtYd"))
    (fp_line (start -0.494 -0.25) (end 0.504 -0.25)
      (stroke (width 0.15) (type solid)) (layer "F.Fab"))
    (fp_line (start -0.494 0.248) (end -0.494 -0.25)
      (stroke (width 0.15) (type solid)) (layer "F.Fab"))
    (fp_line (start 0.504 -0.25) (end 0.504 0.248)
      (stroke (width 0.15) (type solid)) (layer "F.Fab"))
    (fp_line (start 0.504 0.248) (end -0.494 0.248)
      (stroke (width 0.15) (type solid)) (layer "F.Fab"))
    (pad "1" smd roundrect (at -0.48 0 90) (size 0.59 0.64) (layers "F.Cu" "F.Paste" "F.Mask") (roundrect_rratio 0.25)
      (net 1 "GND") (pintype "passive"))
    (pad "2" smd roundrect (at 0.48 0 90) (size 0.59 0.64) (layers "F.Cu" "F.Paste" "F.Mask") (roundrect_rratio 0.25)
      (net 2 "VCC3V3") (pintype "passive"))
  )
	(footprint "antmicro-footprints:R_0603_1608Metric" (layer "F.Cu")
    (at 89.5 79.005 180)
    (descr "Resistor SMD 0603")
    (tags "resistor SMD 0603")
    (property "Author" "Antmicro")
    (property "Current" "1A")
    (property "License" "Apache-2.0")
    (property "MPN" "CR0603-J/-000ELF")
    (property "Manufacturer" "Bourns")
    (property "Public" "False")
    (property "Sheetfile" "power-supply.kicad_sch")
    (property "Sheetname" "Power supply")
    (property "Tolerance" "")
    (property "Val" "0R")
    (property "ki_description" "Zero Ohm Resistor, Jumper, 0603 [1608 Metric], Thick Film, 100 mW, 1 A, Surface Mount Device, CR")
    (property "ki_keywords" "0603, SMT, RESISTOR, PASSIVE")
    (attr smd)
    (fp_text reference "R140" (at -0.26 -1.5) (layer "F.SilkS")
        (effects (font (size 0.7 0.7) (thickness 0.127)))
    )
    (fp_text value "R_0R_0603" (at 0 1.9) (layer "F.Fab")
        (effects (font (size 1 1) (thickness 0.15)))
    )
    (fp_text user "${REFERENCE}" (at -1.25 3.898 180) (layer "F.Fab") hide
        (effects (font (size 0.7 0.7) (thickness 0.15)) (justify left bottom))
    )
    (fp_text user "License: Apache-2.0" (at -1.25 5.9 180) (layer "F.Fab") hide
        (effects (font (size 0.7 0.7) (thickness 0.15)) (justify left bottom))
    )
    (fp_text user "Author: Antmicro" (at -1.25 4.9 180) (layer "F.Fab") hide
        (effects (font (size 0.7 0.7) (thickness 0.15)) (justify left bottom))
    )
    (fp_line (start -0.15 -0.4) (end 0.15 -0.4)
      (stroke (width 0.15) (type solid)) (layer "F.SilkS"))
    (fp_line (start -0.15 0.4) (end 0.15 0.4)
      (stroke (width 0.15) (type solid)) (layer "F.SilkS"))
    (fp_rect (start -1.25 -0.65) (end 1.25 0.65)
      (stroke (width 0.05) (type solid)) (fill none) (layer "F.CrtYd"))
    (fp_rect (start -0.8 -0.4) (end 0.8 0.4)
      (stroke (width 0.15) (type solid)) (fill none) (layer "F.Fab"))
    (pad "1" smd roundrect (at -0.7 0 180) (size 0.8 1) (layers "F.Cu" "F.Paste" "F.Mask") (roundrect_rratio 0.2)
      (net 211 "VCC1V2") (pintype "passive"))
    (pad "2" smd roundrect (at 0.7 0 180) (size 0.8 1) (layers "F.Cu" "F.Paste" "F.Mask") (roundrect_rratio 0.2)
      (net 354 "Net-(C108-Pad2)") (pintype "passive"))
  )
	(footprint "antmicro-footprints:TP_SMD_1mm" (layer "F.Cu")
    (at 77 92.6 180)
    (property "Author" "Antmicro")
    (property "License" "Apache-2.0")
    (property "MPN" "")
    (property "Manufacturer" "")
    (property "Sheetfile" "power-supply.kicad_sch")
    (property "Sheetname" "Power supply")
    (property "exclude_from_bom" "")
    (property "ki_description" "Test point 1mm SMD")
    (property "ki_keywords" "TESTPOINT")
    (attr exclude_from_pos_files exclude_from_bom)
    (fp_text reference "TP8" (at -0.42 -2.665 270) (layer "F.SilkS")
        (effects (font (size 0.7 0.7) (thickness 0.15)) (justify left bottom))
    )
    (fp_text value "TP_1mm_SMD" (at 0 1.4 180) (layer "F.Fab")
        (effects (font (size 0.7 0.7) (thickness 0.15)) (justify left bottom))
    )
    (fp_text user "License: Apache-2.0" (at -0.5 5.2 180) (layer "F.Fab") hide
        (effects (font (size 0.7 0.7) (thickness 0.15)) (justify left bottom))
    )
    (fp_text user "Author: Antmicro" (at -0.5 4 180) (layer "F.Fab") hide
        (effects (font (size 0.7 0.7) (thickness 0.15)) (justify left bottom))
    )
    (fp_text user "${REFERENCE}" (at -0.5 2.8 180) (layer "F.Fab") hide
        (effects (font (size 0.7 0.7) (thickness 0.15)) (justify left bottom))
    )
    (fp_circle (center 0 0) (end 0.6 0)
      (stroke (width 0.05) (type default)) (fill none) (layer "F.CrtYd"))
    (pad "1" smd circle (at 0 0 180) (size 1 1) (layers "F.Cu" "F.Mask")
      (net 355 "Net-(C118-Pad2)") (pinfunction "1") (pintype "passive"))
  )
	(footprint "antmicro-footprints:TP_SMD_1mm" (layer "F.Cu")
    (at 123.2 76.9508)
    (property "Author" "Antmicro")
    (property "License" "Apache-2.0")
    (property "MPN" "")
    (property "Manufacturer" "")
    (property "Sheetfile" "power-supply.kicad_sch")
    (property "Sheetname" "Power supply")
    (property "exclude_from_bom" "")
    (property "ki_description" "Test point 1mm SMD")
    (property "ki_keywords" "TESTPOINT")
    (attr exclude_from_pos_files exclude_from_bom)
    (fp_text reference "TP9" (at -1.02 -0.6758) (layer "F.SilkS")
        (effects (font (size 0.7 0.7) (thickness 0.15)) (justify left bottom))
    )
    (fp_text value "TP_1mm_SMD" (at 0 1.4) (layer "F.Fab")
        (effects (font (size 0.7 0.7) (thickness 0.15)) (justify left bottom))
    )
    (fp_text user "${REFERENCE}" (at -0.5 2.8) (layer "F.Fab") hide
        (effects (font (size 0.7 0.7) (thickness 0.15)) (justify left bottom))
    )
    (fp_text user "Author: Antmicro" (at -0.5 4) (layer "F.Fab") hide
        (effects (font (size 0.7 0.7) (thickness 0.15)) (justify left bottom))
    )
    (fp_text user "License: Apache-2.0" (at -0.5 5.2) (layer "F.Fab") hide
        (effects (font (size 0.7 0.7) (thickness 0.15)) (justify left bottom))
    )
    (fp_circle (center 0 0) (end 0.6 0)
      (stroke (width 0.05) (type default)) (fill none) (layer "F.CrtYd"))
    (pad "1" smd circle (at 0 0) (size 1 1) (layers "F.Cu" "F.Mask")
      (net 356 "Net-(C119-Pad2)") (pinfunction "1") (pintype "passive"))
  )
	(footprint "antmicro-footprints:TP_SMD_1mm" (layer "F.Cu")
    (at 74.64 92.28 180)
    (property "Author" "Antmicro")
    (property "License" "Apache-2.0")
    (property "MPN" "")
    (property "Manufacturer" "")
    (property "Sheetfile" "power-supply.kicad_sch")
    (property "Sheetname" "Power supply")
    (property "exclude_from_bom" "")
    (property "ki_description" "Test point 1mm SMD")
    (property "ki_keywords" "TESTPOINT")
    (attr exclude_from_pos_files exclude_from_bom)
    (fp_text reference "TP10" (at -0.4 -3.245 270) (layer "F.SilkS")
        (effects (font (size 0.7 0.7) (thickness 0.15)) (justify left bottom))
    )
    (fp_text value "TP_1mm_SMD" (at 0 1.4 180) (layer "F.Fab")
        (effects (font (size 0.7 0.7) (thickness 0.15)) (justify left bottom))
    )
    (fp_text user "${REFERENCE}" (at -0.5 2.8 180) (layer "F.Fab") hide
        (effects (font (size 0.7 0.7) (thickness 0.15)) (justify left bottom))
    )
    (fp_text user "License: Apache-2.0" (at -0.5 5.2 180) (layer "F.Fab") hide
        (effects (font (size 0.7 0.7) (thickness 0.15)) (justify left bottom))
    )
    (fp_text user "Author: Antmicro" (at -0.5 4 180) (layer "F.Fab") hide
        (effects (font (size 0.7 0.7) (thickness 0.15)) (justify left bottom))
    )
    (fp_circle (center 0 0) (end 0.6 0)
      (stroke (width 0.05) (type default)) (fill none) (layer "F.CrtYd"))
    (pad "1" smd circle (at 0 0 180) (size 1 1) (layers "F.Cu" "F.Mask")
      (net 357 "Net-(C120-Pad2)") (pinfunction "1") (pintype "passive"))
  )
	(footprint "antmicro-footprints:TP_SMD_1mm" (layer "F.Cu")
    (at 72.2 92.3 180)
    (property "Author" "Antmicro")
    (property "License" "Apache-2.0")
    (property "MPN" "")
    (property "Manufacturer" "")
    (property "Sheetfile" "power-supply.kicad_sch")
    (property "Sheetname" "Power supply")
    (property "exclude_from_bom" "")
    (property "ki_description" "Test point 1mm SMD")
    (property "ki_keywords" "TESTPOINT")
    (attr exclude_from_pos_files exclude_from_bom)
    (fp_text reference "TP11" (at 3.03 -0.645 180) (layer "F.SilkS")
        (effects (font (size 0.7 0.7) (thickness 0.15)) (justify left bottom))
    )
    (fp_text value "TP_1mm_SMD" (at 0 1.4 180) (layer "F.Fab")
        (effects (font (size 0.7 0.7) (thickness 0.15)) (justify left bottom))
    )
    (fp_text user "${REFERENCE}" (at -0.5 2.8 180) (layer "F.Fab") hide
        (effects (font (size 0.7 0.7) (thickness 0.15)) (justify left bottom))
    )
    (fp_text user "Author: Antmicro" (at -0.5 4 180) (layer "F.Fab") hide
        (effects (font (size 0.7 0.7) (thickness 0.15)) (justify left bottom))
    )
    (fp_text user "License: Apache-2.0" (at -0.5 5.2 180) (layer "F.Fab") hide
        (effects (font (size 0.7 0.7) (thickness 0.15)) (justify left bottom))
    )
    (fp_circle (center 0 0) (end 0.6 0)
      (stroke (width 0.05) (type default)) (fill none) (layer "F.CrtYd"))
    (pad "1" smd circle (at 0 0 180) (size 1 1) (layers "F.Cu" "F.Mask")
      (net 358 "Net-(C121-Pad2)") (pinfunction "1") (pintype "passive"))
  )
	(footprint "antmicro-footprints:R_0402_1005Metric" (layer "F.Cu")
    (at 76.4 61.2)
    (descr "Resistor SMD 0402")
    (tags "resistor SMD 0402")
    (property "Author" "Antmicro")
    (property "License" "Apache-2.0")
    (property "MPN" "CR0402-FX-5362GLF")
    (property "Manufacturer" "Bourns")
    (property "Public" "False")
    (property "Sheetfile" "power-supply.kicad_sch")
    (property "Sheetname" "Power supply")
    (property "Tolerance" "1%")
    (property "Val" "53k6")
    (property "ki_description" "SMD Chip Resistor")
    (property "ki_keywords" "0402, SMT, RESISTOR, PASSIVE")
    (attr smd)
    (fp_text reference "R96" (at 0.18 -1.765) (layer "F.SilkS")
        (effects (font (size 0.7 0.7) (thickness 0.127)))
    )
    (fp_text value "R_53k6_0402" (at 0 1.17) (layer "F.Fab")
        (effects (font (size 1 1) (thickness 0.15)))
    )
    (fp_text user "License: Apache-2.0" (at -0.95 5.169) (layer "F.Fab") hide
        (effects (font (size 0.7 0.7) (thickness 0.15)) (justify left bottom))
    )
    (fp_text user "${REFERENCE}" (at 0 0) (layer "F.Fab")
        (effects (font (size 0.25 0.25) (thickness 0.04)))
    )
    (fp_text user "Author: Antmicro" (at -0.95 4.169) (layer "F.Fab") hide
        (effects (font (size 0.7 0.7) (thickness 0.15)) (justify left bottom))
    )
    (fp_rect (start -0.925 -0.47) (end 0.925 0.47)
      (stroke (width 0.05) (type default)) (fill none) (layer "F.CrtYd"))
    (fp_rect (start -0.5 -0.25) (end 0.5 0.25)
      (stroke (width 0.15) (type solid)) (fill none) (layer "F.Fab"))
    (pad "1" smd roundrect (at -0.48 0) (size 0.59 0.64) (layers "F.Cu" "F.Paste" "F.Mask") (roundrect_rratio 0.25)
      (net 364 "Net-(R95-Pad2)") (pintype "passive"))
    (pad "2" smd roundrect (at 0.48 0) (size 0.59 0.64) (layers "F.Cu" "F.Paste" "F.Mask") (roundrect_rratio 0.25)
      (net 784 "Net-(U15-FB)") (pintype "passive"))
  )
	(footprint "antmicro-footprints:C_0402_1005Metric" (layer "F.Cu")
    (at 74 63.4)
    (descr "Capacitor SMD 0402")
    (tags "capacitor SMD 0402")
    (property "Author" "Antmicro")
    (property "Dielectric" "C0G")
    (property "License" "Apache-2.0")
    (property "MPN" "C0402C470J5GACTU")
    (property "Manufacturer" "KEMET")
    (property "Public" "False")
    (property "Sheetfile" "power-supply.kicad_sch")
    (property "Sheetname" "Power supply")
    (property "Val" "47p")
    (property "Voltage" "")
    (property "ki_description" "SMD Multilayer Ceramic Capacitor, 47 pF, 50 V, 0402 [1005 Metric], ± 5%, C0G / NP0, C Series KEMET")
    (property "ki_keywords" "0402, SMT, CAPACITOR, PASSIVE, CERAMIC, MLCC")
    (attr smd)
    (fp_text reference "C104" (at -0.2 2.465) (layer "F.SilkS")
        (effects (font (size 0.7 0.7) (thickness 0.127)))
    )
    (fp_text value "C_47p_0402" (at 0 1.17) (layer "F.Fab")
        (effects (font (size 1 1) (thickness 0.15)))
    )
    (fp_text user "${REFERENCE}" (at 0 0) (layer "F.Fab")
        (effects (font (size 0.25 0.25) (thickness 0.04)))
    )
    (fp_text user "Author: Antmicro" (at -0.939 3.399) (layer "F.Fab") hide
        (effects (font (size 0.7 0.7) (thickness 0.15)) (justify left bottom))
    )
    (fp_text user "License: Apache-2.0" (at -0.939 5.799) (layer "F.Fab") hide
        (effects (font (size 0.7 0.7) (thickness 0.15)) (justify left bottom))
    )
    (fp_rect (start -0.925 -0.47) (end 0.925 0.47)
      (stroke (width 0.05) (type default)) (fill none) (layer "F.CrtYd"))
    (fp_line (start -0.494 -0.25) (end 0.504 -0.25)
      (stroke (width 0.15) (type solid)) (layer "F.Fab"))
    (fp_line (start -0.494 0.248) (end -0.494 -0.25)
      (stroke (width 0.15) (type solid)) (layer "F.Fab"))
    (fp_line (start 0.504 -0.25) (end 0.504 0.248)
      (stroke (width 0.15) (type solid)) (layer "F.Fab"))
    (fp_line (start 0.504 0.248) (end -0.494 0.248)
      (stroke (width 0.15) (type solid)) (layer "F.Fab"))
    (pad "1" smd roundrect (at -0.48 0) (size 0.59 0.64) (layers "F.Cu" "F.Paste" "F.Mask") (roundrect_rratio 0.25)
      (net 1 "GND") (pintype "passive"))
    (pad "2" smd roundrect (at 0.48 0) (size 0.59 0.64) (layers "F.Cu" "F.Paste" "F.Mask") (roundrect_rratio 0.25)
      (net 781 "Net-(U15-COMP)") (pintype "passive"))
  )
)
